G04 ================== begin FILE IDENTIFICATION RECORD ==================*
G04 Layout Name:  D:/<user>/Wistron_project/16347-sc/gbr/16347-sc.brd*
G04 Film Name:    BMASK*
G04 File Format:  Gerber RS274X*
G04 File Origin:  Cadence Allegro 16.5-S056*
G04 Origin Date:  Tue Mar 14 17:08:15 2017*
G04 *
G04 Layer:  VIA CLASS/SOLDERMASK_BOTTOM*
G04 Layer:  PIN/SOLDERMASK_BOTTOM*
G04 Layer:  PACKAGE GEOMETRY/SOLDERMASK_BOTTOM*
G04 Layer:  DRAWING FORMAT/LAYER_PCB_STORY*
G04 Layer:  DRAWING FORMAT/LAYER_SOLDER_B*
G04 Layer:  BOARD GEOMETRY/SOLDERMASK_BOTTOM*
G04 *
G04 Offset:    (0.00 0.00)*
G04 Mirror:    No*
G04 Mode:      Positive*
G04 Rotation:  0*
G04 FullContactRelief:  No*
G04 UndefLineWidth:     6.00*
G04 ================== end FILE IDENTIFICATION RECORD ====================*
%FSLAX35Y35*MOIN*%
%IR0*IPPOS*OFA0.00000B0.00000*MIA0B0*SFA1.00000B1.00000*%
%AMMACRO22*
4,1,40,.013,-.017,
-.013,-.017,
-.013695,-.016939,
-.014368,-.016759,
-.015,-.016464,
-.015571,-.016064,
-.016064,-.015571,
-.016464,-.015,
-.016759,-.014368,
-.016939,-.013695,
-.017,-.013,
-.017,.013,
-.016939,.013695,
-.016759,.014368,
-.016464,.015,
-.016064,.015571,
-.015571,.016064,
-.015,.016464,
-.014368,.016759,
-.013695,.016939,
-.013,.017,
.013,.017,
.013695,.016939,
.014368,.016759,
.015,.016464,
.015571,.016064,
.016064,.015571,
.016464,.015,
.016759,.014368,
.016939,.013695,
.017,.013,
.017,-.013,
.016939,-.013695,
.016759,-.014368,
.016464,-.015,
.016064,-.015571,
.015571,-.016064,
.015,-.016464,
.014368,-.016759,
.013695,-.016939,
.013,-.017,
0.0*
%
%ADD22MACRO22*%
%AMMACRO17*
4,1,40,-.017,-.013,
-.017,.013,
-.016939,.013695,
-.016759,.014368,
-.016464,.015,
-.016064,.015571,
-.015571,.016064,
-.015,.016464,
-.014368,.016759,
-.013695,.016939,
-.013,.017,
.013,.017,
.013695,.016939,
.014368,.016759,
.015,.016464,
.015571,.016064,
.016064,.015571,
.016464,.015,
.016759,.014368,
.016939,.013695,
.017,.013,
.017,-.013,
.016939,-.013695,
.016759,-.014368,
.016464,-.015,
.016064,-.015571,
.015571,-.016064,
.015,-.016464,
.014368,-.016759,
.013695,-.016939,
.013,-.017,
-.013,-.017,
-.013695,-.016939,
-.014368,-.016759,
-.015,-.016464,
-.015571,-.016064,
-.016064,-.015571,
-.016464,-.015,
-.016759,-.014368,
-.016939,-.013695,
-.017,-.013,
0.0*
%
%ADD17MACRO17*%
%ADD18C,.024*%
%ADD13C,.08*%
%ADD10C,.086*%
%AMMACRO16*
4,1,40,.007,-.0225,
.008389,-.022378,
.009736,-.022018,
.011,-.021428,
.012142,-.020628,
.013128,-.019642,
.013928,-.0185,
.014518,-.017236,
.014878,-.015889,
.015,-.0145,
.015,.0145,
.014878,.015889,
.014518,.017236,
.013928,.0185,
.013128,.019642,
.012142,.020628,
.011,.021428,
.009736,.022018,
.008389,.022378,
.007,.0225,
-.007,.0225,
-.008389,.022378,
-.009736,.022018,
-.011,.021428,
-.012142,.020628,
-.013128,.019642,
-.013928,.0185,
-.014518,.017236,
-.014878,.015889,
-.015,.0145,
-.015,-.0145,
-.014878,-.015889,
-.014518,-.017236,
-.013928,-.0185,
-.013128,-.019642,
-.012142,-.020628,
-.011,-.021428,
-.009736,-.022018,
-.008389,-.022378,
-.007,-.0225,
.007,-.0225,
0.0*
%
%ADD16MACRO16*%
%AMMACRO14*
4,1,40,.007,-.011,
-.007,-.011,
-.007695,-.010939,
-.008368,-.010759,
-.009,-.010464,
-.009571,-.010064,
-.010064,-.009571,
-.010464,-.009,
-.010759,-.008368,
-.010939,-.007695,
-.011,-.007,
-.011,.007,
-.010939,.007695,
-.010759,.008368,
-.010464,.009,
-.010064,.009571,
-.009571,.010064,
-.009,.010464,
-.008368,.010759,
-.007695,.010939,
-.007,.011,
.007,.011,
.007695,.010939,
.008368,.010759,
.009,.010464,
.009571,.010064,
.010064,.009571,
.010464,.009,
.010759,.008368,
.010939,.007695,
.011,.007,
.011,-.007,
.010939,-.007695,
.010759,-.008368,
.010464,-.009,
.010064,-.009571,
.009571,-.010064,
.009,-.010464,
.008368,-.010759,
.007695,-.010939,
.007,-.011,
0.0*
%
%ADD14MACRO14*%
%AMMACRO15*
4,1,40,.007,-.011,
-.007,-.011,
-.007695,-.010939,
-.008368,-.010759,
-.009,-.010464,
-.009571,-.010064,
-.010064,-.009571,
-.010464,-.009,
-.010759,-.008368,
-.010939,-.007695,
-.011,-.007,
-.011,.007,
-.010939,.007695,
-.010759,.008368,
-.010464,.009,
-.010064,.009571,
-.009571,.010064,
-.009,.010464,
-.008368,.010759,
-.007695,.010939,
-.007,.011,
.007,.011,
.007695,.010939,
.008368,.010759,
.009,.010464,
.009571,.010064,
.010064,.009571,
.010464,.009,
.010759,.008368,
.010939,.007695,
.011,.007,
.011,-.007,
.010939,-.007695,
.010759,-.008368,
.010464,-.009,
.010064,-.009571,
.009571,-.010064,
.009,-.010464,
.008368,-.010759,
.007695,-.010939,
.007,-.011,
0.0*
%
%ADD15MACRO15*%
%ADD20R,.05X.065*%
%ADD12C,.115*%
%ADD24R,.024X.059*%
%ADD11C,.237*%
%ADD23R,.059X.079*%
%AMMACRO21*
4,1,40,.013,-.017,
-.013,-.017,
-.013695,-.016939,
-.014368,-.016759,
-.015,-.016464,
-.015571,-.016064,
-.016064,-.015571,
-.016464,-.015,
-.016759,-.014368,
-.016939,-.013695,
-.017,-.013,
-.017,.013,
-.016939,.013695,
-.016759,.014368,
-.016464,.015,
-.016064,.015571,
-.015571,.016064,
-.015,.016464,
-.014368,.016759,
-.013695,.016939,
-.013,.017,
.013,.017,
.013695,.016939,
.014368,.016759,
.015,.016464,
.015571,.016064,
.016064,.015571,
.016464,.015,
.016759,.014368,
.016939,.013695,
.017,.013,
.017,-.013,
.016939,-.013695,
.016759,-.014368,
.016464,-.015,
.016064,-.015571,
.015571,-.016064,
.015,-.016464,
.014368,-.016759,
.013695,-.016939,
.013,-.017,
0.0*
%
%ADD21MACRO21*%
%AMMACRO19*
4,1,40,-.017,-.013,
-.017,.013,
-.016939,.013695,
-.016759,.014368,
-.016464,.015,
-.016064,.015571,
-.015571,.016064,
-.015,.016464,
-.014368,.016759,
-.013695,.016939,
-.013,.017,
.013,.017,
.013695,.016939,
.014368,.016759,
.015,.016464,
.015571,.016064,
.016064,.015571,
.016464,.015,
.016759,.014368,
.016939,.013695,
.017,.013,
.017,-.013,
.016939,-.013695,
.016759,-.014368,
.016464,-.015,
.016064,-.015571,
.015571,-.016064,
.015,-.016464,
.014368,-.016759,
.013695,-.016939,
.013,-.017,
-.013,-.017,
-.013695,-.016939,
-.014368,-.016759,
-.015,-.016464,
-.015571,-.016064,
-.016064,-.015571,
-.016464,-.015,
-.016759,-.014368,
-.016939,-.013695,
-.017,-.013,
0.0*
%
%ADD19MACRO19*%
%ADD25C,.02*%
%ADD26C,.006*%
G75*
%LPD*%
G75*
G54D10*
X35185Y15572D03*
X16240Y99213D03*
Y233859D03*
Y368505D03*
Y503151D03*
Y637797D03*
Y772443D03*
Y907089D03*
X693024Y26550D03*
X784745Y19685D03*
Y154331D03*
Y288977D03*
Y423623D03*
Y558269D03*
Y692915D03*
Y827561D03*
G54D11*
X16240Y19684D03*
X301968Y19685D03*
X488681Y19684D03*
X712106D03*
G54D20*
X146000Y19500D03*
X157000D03*
G54D21*
X149700Y26300D03*
G54D12*
X47737Y19685D03*
X680610D03*
G54D13*
X35851Y28624D03*
X48411Y920770D03*
X693601Y10159D03*
X751130Y826309D03*
X765026Y19107D03*
G54D22*
X155300Y26300D03*
G54D23*
X167913Y40748D03*
X219095D03*
G54D14*
X74500Y11400D03*
X88400Y11800D03*
X115000Y10400D03*
X127800D03*
X253011Y12770D03*
X268522Y12786D03*
X418100Y13800D03*
X432200D03*
X558300Y13000D03*
X544800D03*
X651700Y12500D03*
X636600Y12300D03*
G54D24*
X175787Y34842D03*
X179724D03*
X183661D03*
X175787Y58858D03*
X179724D03*
X183661D03*
X187598Y34842D03*
X191535D03*
X195473D03*
X199410D03*
X203347D03*
X207284D03*
X211221D03*
X187598Y58858D03*
X191535D03*
X195473D03*
X199410D03*
X203347D03*
X207284D03*
X211221D03*
G54D15*
X77900Y11400D03*
X118400Y10400D03*
X91800Y11800D03*
X131200Y10400D03*
X256411Y12770D03*
X271922Y12786D03*
X421500Y13800D03*
X435600D03*
X561700Y13000D03*
X548200D03*
X655100Y12500D03*
X640000Y12300D03*
G54D25*
G01X-23515Y-108314D02*
X-55515D01*
G01X-23515Y-124314D02*
Y-204314D01*
G01D02*
X1177585D01*
G01X-27515Y-108314D02*
G02I-12000J0D01*
G01X-39515Y-124314D02*
Y-92314D01*
G01X-23515Y-124314D02*
X1177585D01*
G01X-23515Y-159814D02*
X1177585D01*
G01X-32665Y-108314D02*
G02I-6850J0D01*
G01X390085Y-124314D02*
Y-204314D01*
G01X527585Y-124314D02*
Y-204314D01*
G01X642585Y-124314D02*
Y-204314D01*
G01X810085Y-124314D02*
Y-204314D01*
G01X980085Y-124314D02*
Y-204314D01*
G01X1177585Y-124314D02*
Y-204314D01*
G01X1205585Y-108314D02*
G02I-12000J0D01*
G01X1200435D02*
G02I-6850J0D01*
G01X1209585D02*
X1177585D01*
G01X1193585Y-124314D02*
Y-92314D01*
G54D16*
X87800Y25050D03*
X83925Y17550D03*
X73700Y25050D03*
X77575Y17550D03*
X69825D03*
X126100Y23650D03*
X129975Y16150D03*
X122225D03*
X91675Y17550D03*
X112000Y23650D03*
X115875Y16150D03*
X108125D03*
X255107Y26004D03*
X258982Y18504D03*
X251232D03*
X269207Y26004D03*
X273082Y18504D03*
X265332D03*
X422775Y19550D03*
X415025D03*
X418900Y27050D03*
X436975Y19550D03*
X429225D03*
X433100Y27050D03*
X563175Y18750D03*
X555425D03*
X548975D03*
X541225D03*
X559300Y26250D03*
X545100D03*
X651700Y25750D03*
X655575Y18250D03*
X647825D03*
X637500Y25750D03*
X641375Y18250D03*
X633625D03*
G54D26*
G01X981Y-184981D02*
X1855Y-184106D01*
X2510Y-182648D01*
X2947Y-180605D01*
X2510Y-178856D01*
X1637Y-177689D01*
X108Y-176814D01*
X-5787D01*
Y-194314D01*
X1418D01*
X2947Y-193148D01*
X3820Y-191397D01*
X4257Y-189356D01*
X3820Y-187314D01*
X2510Y-185564D01*
X981Y-184981D01*
X-5787D01*
G01X13678Y-194314D02*
Y-182648D01*
G01Y-184981D02*
X14770Y-183814D01*
X15862Y-182939D01*
X17390Y-182648D01*
X18481Y-182939D01*
X19792Y-183814D01*
G01X29650Y-199564D02*
X30960Y-200147D01*
X32707Y-199564D01*
X33798Y-198398D01*
X34672Y-196939D01*
X35981Y-192273D01*
X38820Y-182648D01*
G01X31833D02*
X35981Y-192273D01*
G01X55228Y-184106D02*
X53700Y-182939D01*
X52390Y-182648D01*
X50643Y-183231D01*
X49333Y-184397D01*
X48460Y-186439D01*
X48241Y-188481D01*
X48460Y-190523D01*
X49333Y-192273D01*
X50643Y-193731D01*
X52390Y-194314D01*
X53918Y-193731D01*
X55228Y-192564D01*
G01X65960Y-186439D02*
X72947D01*
X72292Y-184397D01*
X71200Y-183231D01*
X69672Y-182648D01*
X68143Y-182939D01*
X66833Y-183814D01*
X65960Y-185856D01*
X65523Y-187606D01*
Y-189356D01*
X65960Y-191106D01*
X67052Y-192856D01*
X68362Y-194022D01*
X69890Y-194314D01*
X71418Y-193731D01*
X72947Y-191981D01*
G01X109038Y-178273D02*
X107728Y-177397D01*
X106200Y-176814D01*
X104453D01*
X102488Y-177689D01*
X100960Y-179147D01*
X99868Y-180898D01*
X98995Y-183814D01*
X98776Y-186439D01*
X99213Y-189064D01*
X99868Y-190814D01*
X101178Y-192564D01*
X102707Y-193731D01*
X104235Y-194314D01*
X105763D01*
X107292Y-193731D01*
X108602Y-192856D01*
X109694Y-191690D01*
G01X125665Y-194314D02*
Y-182648D01*
G01Y-184689D02*
X124792Y-183523D01*
X123481Y-182939D01*
X121953Y-182648D01*
X120425Y-183231D01*
X119115Y-184397D01*
X118241Y-186147D01*
X117805Y-188481D01*
X118241Y-190814D01*
X119115Y-192564D01*
X120425Y-193731D01*
X121953Y-194314D01*
X123481Y-194022D01*
X124792Y-193148D01*
X125665Y-191981D01*
G01X135523Y-194314D02*
Y-182648D01*
G01Y-185564D02*
X136397Y-184106D01*
X137707Y-182939D01*
X139453Y-182648D01*
X140981Y-182939D01*
X142292Y-184106D01*
X142947Y-186147D01*
Y-194314D01*
G01X152150Y-199564D02*
X153460Y-200147D01*
X155207Y-199564D01*
X156298Y-198398D01*
X157172Y-196939D01*
X158481Y-192273D01*
X161320Y-182648D01*
G01X154333D02*
X158481Y-192273D01*
G01X174235Y-194314D02*
X172925Y-194022D01*
X171615Y-192856D01*
X170741Y-190814D01*
X170305Y-188481D01*
X170741Y-186147D01*
X171615Y-184106D01*
X172925Y-182939D01*
X174235Y-182648D01*
X175545Y-182939D01*
X176855Y-184106D01*
X177728Y-186147D01*
X177947Y-188481D01*
X177728Y-190814D01*
X176855Y-192856D01*
X175545Y-194022D01*
X174235Y-194314D01*
G01X188023D02*
Y-182648D01*
G01Y-185564D02*
X188897Y-184106D01*
X190207Y-182939D01*
X191953Y-182648D01*
X193481Y-182939D01*
X194792Y-184106D01*
X195447Y-186147D01*
Y-194314D01*
G01X222368Y-176814D02*
Y-194314D01*
X231102D01*
G01X248602D02*
X239868D01*
Y-176814D01*
X248602D01*
G01X245108Y-185272D02*
X239868D01*
G01X256932Y-194314D02*
Y-176814D01*
X261298D01*
X263045Y-177689D01*
X264355Y-178856D01*
X265447Y-180605D01*
X266320Y-182648D01*
X266538Y-185564D01*
X266320Y-188481D01*
X265447Y-190523D01*
X264355Y-192273D01*
X263045Y-193439D01*
X261298Y-194314D01*
X256932D01*
G01X298481Y-184981D02*
X299355Y-184106D01*
X300010Y-182648D01*
X300447Y-180605D01*
X300010Y-178856D01*
X299137Y-177689D01*
X297608Y-176814D01*
X291713D01*
Y-194314D01*
X298918D01*
X300447Y-193148D01*
X301320Y-191397D01*
X301757Y-189356D01*
X301320Y-187314D01*
X300010Y-185564D01*
X298481Y-184981D01*
X291713D01*
G01X314235Y-194314D02*
X312925Y-194022D01*
X311615Y-192856D01*
X310741Y-190814D01*
X310305Y-188481D01*
X310741Y-186147D01*
X311615Y-184106D01*
X312925Y-182939D01*
X314235Y-182648D01*
X315545Y-182939D01*
X316855Y-184106D01*
X317728Y-186147D01*
X317947Y-188481D01*
X317728Y-190814D01*
X316855Y-192856D01*
X315545Y-194022D01*
X314235Y-194314D01*
G01X335665D02*
Y-182648D01*
G01Y-184689D02*
X334792Y-183523D01*
X333481Y-182939D01*
X331953Y-182648D01*
X330425Y-183231D01*
X329115Y-184397D01*
X328241Y-186147D01*
X327805Y-188481D01*
X328241Y-190814D01*
X329115Y-192564D01*
X330425Y-193731D01*
X331953Y-194314D01*
X333481Y-194022D01*
X334792Y-193148D01*
X335665Y-191981D01*
G01X346178Y-194314D02*
Y-182648D01*
G01Y-184981D02*
X347270Y-183814D01*
X348362Y-182939D01*
X349890Y-182648D01*
X350981Y-182939D01*
X352292Y-183814D01*
G01X370665Y-176814D02*
Y-194314D01*
G01Y-191690D02*
X369792Y-193148D01*
X368481Y-194022D01*
X366953Y-194314D01*
X365207Y-193731D01*
X363897Y-192273D01*
X363023Y-190523D01*
X362805Y-188481D01*
X363023Y-186439D01*
X363897Y-184689D01*
X365207Y-183231D01*
X366953Y-182648D01*
X368481Y-182939D01*
X369573Y-183523D01*
X370665Y-184689D01*
G01X142308Y-149314D02*
Y-131814D01*
X147985Y-146397D01*
X153662Y-131814D01*
Y-149314D01*
G01X165485D02*
X164175Y-149022D01*
X162865Y-147856D01*
X161991Y-145814D01*
X161555Y-143481D01*
X161991Y-141147D01*
X162865Y-139106D01*
X164175Y-137939D01*
X165485Y-137648D01*
X166795Y-137939D01*
X168105Y-139106D01*
X168978Y-141147D01*
X169197Y-143481D01*
X168978Y-145814D01*
X168105Y-147856D01*
X166795Y-149022D01*
X165485Y-149314D01*
G01X186915Y-131814D02*
Y-149314D01*
G01Y-146690D02*
X186042Y-148148D01*
X184731Y-149022D01*
X183203Y-149314D01*
X181457Y-148731D01*
X180147Y-147273D01*
X179273Y-145523D01*
X179055Y-143481D01*
X179273Y-141439D01*
X180147Y-139689D01*
X181457Y-138231D01*
X183203Y-137648D01*
X184731Y-137939D01*
X185823Y-138523D01*
X186915Y-139689D01*
G01X197210Y-141439D02*
X204197D01*
X203542Y-139397D01*
X202450Y-138231D01*
X200922Y-137648D01*
X199393Y-137939D01*
X198083Y-138814D01*
X197210Y-140856D01*
X196773Y-142606D01*
Y-144356D01*
X197210Y-146106D01*
X198302Y-147856D01*
X199612Y-149022D01*
X201140Y-149314D01*
X202668Y-148731D01*
X204197Y-146981D01*
G01X217985Y-149314D02*
Y-131814D01*
G01X423785Y-194314D02*
Y-176814D01*
X421165Y-180314D01*
G01Y-194314D02*
X426405D01*
G01X437137Y-187023D02*
X438665Y-184981D01*
X439975Y-183814D01*
X441722Y-183231D01*
X443250Y-183814D01*
X444342Y-184981D01*
X445215Y-186731D01*
X445433Y-188772D01*
X445215Y-190523D01*
X444342Y-192273D01*
X443031Y-193731D01*
X441503Y-194314D01*
X439757Y-193731D01*
X438228Y-191981D01*
X437355Y-189356D01*
X437137Y-186439D01*
X437573Y-182648D01*
X438228Y-180605D01*
X439320Y-178564D01*
X440848Y-177106D01*
X442377Y-176814D01*
X443905Y-177397D01*
X444997Y-178856D01*
G01X453982Y-190814D02*
X455291Y-192856D01*
X457038Y-194022D01*
X459003Y-194314D01*
X460750Y-194022D01*
X462497Y-192564D01*
X463588Y-190814D01*
X463807Y-189064D01*
X463370Y-187023D01*
X461842Y-185564D01*
X460313Y-184981D01*
X458348D01*
G01X460313D02*
X461623Y-184106D01*
X462715Y-182648D01*
X463152Y-180898D01*
X462715Y-179147D01*
X461623Y-177689D01*
X459658Y-176814D01*
X457693Y-177106D01*
X455728Y-178273D01*
G01X478905Y-194314D02*
Y-176814D01*
X470826Y-189356D01*
X481744D01*
G01X493348Y-194314D02*
X493785Y-190523D01*
X494440Y-187314D01*
X495313Y-184397D01*
X496405Y-181189D01*
X498152Y-176814D01*
X489418D01*
G01X410668Y-149314D02*
Y-131814D01*
X415908D01*
X417655Y-132689D01*
X418965Y-134731D01*
X419402Y-137064D01*
X418965Y-139397D01*
X417873Y-141147D01*
X415908Y-142023D01*
X410668D01*
G01X437338Y-133273D02*
X436028Y-132397D01*
X434500Y-131814D01*
X432753D01*
X430788Y-132689D01*
X429260Y-134147D01*
X428168Y-135898D01*
X427295Y-138814D01*
X427076Y-141439D01*
X427513Y-144064D01*
X428168Y-145814D01*
X429478Y-147564D01*
X431007Y-148731D01*
X432535Y-149314D01*
X434063D01*
X435592Y-148731D01*
X436902Y-147856D01*
X437994Y-146690D01*
G01X451781Y-139981D02*
X452655Y-139106D01*
X453310Y-137648D01*
X453747Y-135605D01*
X453310Y-133856D01*
X452437Y-132689D01*
X450908Y-131814D01*
X445013D01*
Y-149314D01*
X452218D01*
X453747Y-148148D01*
X454620Y-146397D01*
X455057Y-144356D01*
X454620Y-142314D01*
X453310Y-140564D01*
X451781Y-139981D01*
X445013D01*
G01X460985Y-155147D02*
X474085D01*
G01X480013Y-149314D02*
Y-131814D01*
X490057Y-149314D01*
Y-131814D01*
G01X502535Y-149314D02*
X500788Y-149022D01*
X499260Y-147856D01*
X497950Y-146106D01*
X497076Y-144064D01*
X496640Y-141731D01*
Y-139397D01*
X497076Y-137064D01*
X497950Y-135022D01*
X499260Y-133273D01*
X500788Y-132106D01*
X502535Y-131814D01*
X504281Y-132106D01*
X505810Y-133273D01*
X507120Y-135022D01*
X507994Y-137064D01*
X508430Y-139397D01*
Y-141731D01*
X507994Y-144064D01*
X507120Y-146106D01*
X505810Y-147856D01*
X504281Y-149022D01*
X502535Y-149314D01*
G01X553376Y-131814D02*
X558835Y-149314D01*
X564294Y-131814D01*
G01X580702Y-149314D02*
X571968D01*
Y-131814D01*
X580702D01*
G01X577208Y-140272D02*
X571968D01*
G01X589468Y-149314D02*
Y-131814D01*
X594927D01*
X596673Y-132689D01*
X597765Y-133856D01*
X598202Y-136189D01*
X597765Y-138523D01*
X596455Y-139981D01*
X594927Y-140856D01*
X589468D01*
G01X594927D02*
X598202Y-149314D01*
G01X611335Y-149897D02*
X610898Y-149606D01*
Y-149022D01*
X611335Y-148731D01*
X611772Y-149022D01*
Y-149606D01*
X611335Y-149897D01*
G01X571750Y-191981D02*
X573497Y-193439D01*
X575462Y-194314D01*
X577208D01*
X578955Y-193439D01*
X580265Y-191981D01*
X580920Y-189939D01*
X580483Y-187898D01*
X579392Y-186147D01*
X577427Y-184981D01*
X574807Y-184397D01*
X573278Y-183231D01*
X572623Y-181189D01*
X573060Y-179147D01*
X574152Y-177689D01*
X575680Y-176814D01*
X577208D01*
X578737Y-177397D01*
X580047Y-178856D01*
G01X598638Y-178273D02*
X597328Y-177397D01*
X595800Y-176814D01*
X594053D01*
X592088Y-177689D01*
X590560Y-179147D01*
X589468Y-180898D01*
X588595Y-183814D01*
X588376Y-186439D01*
X588813Y-189064D01*
X589468Y-190814D01*
X590778Y-192564D01*
X592307Y-193731D01*
X593835Y-194314D01*
X595363D01*
X596892Y-193731D01*
X598202Y-192856D01*
X599294Y-191690D01*
G01X759539Y-184981D02*
X758665Y-184106D01*
X758010Y-182648D01*
X757573Y-180605D01*
X758010Y-178856D01*
X758883Y-177689D01*
X760412Y-176814D01*
X766307D01*
Y-194314D01*
X759102D01*
X757573Y-193148D01*
X756700Y-191397D01*
X756263Y-189356D01*
X756700Y-187314D01*
X758010Y-185564D01*
X759539Y-184981D01*
X766307D01*
G01X749462Y-194314D02*
Y-176814D01*
X743785Y-191397D01*
X738108Y-176814D01*
Y-194314D01*
G01X731744D02*
X726285Y-176814D01*
X720826Y-194314D01*
G01X722792Y-188189D02*
X729779D01*
G01X713370Y-191981D02*
X711623Y-193439D01*
X709658Y-194314D01*
X707912D01*
X706165Y-193439D01*
X704855Y-191981D01*
X704200Y-189939D01*
X704637Y-187898D01*
X705728Y-186147D01*
X707693Y-184981D01*
X710313Y-184397D01*
X711842Y-183231D01*
X712497Y-181189D01*
X712060Y-179147D01*
X710968Y-177689D01*
X709440Y-176814D01*
X707912D01*
X706383Y-177397D01*
X705073Y-178856D01*
G01X696088Y-194314D02*
Y-176814D01*
G01X687792D02*
X696088Y-187606D01*
G01X686482Y-194314D02*
X692377Y-182648D01*
G01X686918Y-131814D02*
Y-149314D01*
X695652D01*
G01X712715D02*
Y-137648D01*
G01Y-139689D02*
X711842Y-138523D01*
X710531Y-137939D01*
X709003Y-137648D01*
X707475Y-138231D01*
X706165Y-139397D01*
X705291Y-141147D01*
X704855Y-143481D01*
X705291Y-145814D01*
X706165Y-147564D01*
X707475Y-148731D01*
X709003Y-149314D01*
X710531Y-149022D01*
X711842Y-148148D01*
X712715Y-146981D01*
G01X721700Y-154564D02*
X723010Y-155147D01*
X724757Y-154564D01*
X725848Y-153398D01*
X726722Y-151939D01*
X728031Y-147273D01*
X730870Y-137648D01*
G01X723883D02*
X728031Y-147273D01*
G01X740510Y-141439D02*
X747497D01*
X746842Y-139397D01*
X745750Y-138231D01*
X744222Y-137648D01*
X742693Y-137939D01*
X741383Y-138814D01*
X740510Y-140856D01*
X740073Y-142606D01*
Y-144356D01*
X740510Y-146106D01*
X741602Y-147856D01*
X742912Y-149022D01*
X744440Y-149314D01*
X745968Y-148731D01*
X747497Y-146981D01*
G01X758228Y-149314D02*
Y-137648D01*
G01Y-139981D02*
X759320Y-138814D01*
X760412Y-137939D01*
X761940Y-137648D01*
X763031Y-137939D01*
X764342Y-138814D01*
G01X851335Y-194314D02*
X849588Y-194022D01*
X848060Y-192856D01*
X846750Y-191106D01*
X845876Y-189064D01*
X845440Y-186731D01*
Y-184397D01*
X845876Y-182064D01*
X846750Y-180022D01*
X848060Y-178273D01*
X849588Y-177106D01*
X851335Y-176814D01*
X853081Y-177106D01*
X854610Y-178273D01*
X855920Y-180022D01*
X856794Y-182064D01*
X857230Y-184397D01*
Y-186731D01*
X856794Y-189064D01*
X855920Y-191106D01*
X854610Y-192856D01*
X853081Y-194022D01*
X851335Y-194314D01*
G01X853081Y-189647D02*
X855702Y-194314D01*
G01X864032Y-176814D02*
Y-189356D01*
X864905Y-191981D01*
X866652Y-193731D01*
X868835Y-194314D01*
X871018Y-193731D01*
X872765Y-191981D01*
X873638Y-189356D01*
Y-176814D01*
G01X883715D02*
X888955D01*
G01X886335D02*
Y-194314D01*
G01X883715D02*
X888955D01*
G01X898813D02*
Y-176814D01*
X908857Y-194314D01*
Y-176814D01*
G01X926138Y-178273D02*
X924828Y-177397D01*
X923300Y-176814D01*
X921553D01*
X919588Y-177689D01*
X918060Y-179147D01*
X916968Y-180898D01*
X916095Y-183814D01*
X915876Y-186439D01*
X916313Y-189064D01*
X916968Y-190814D01*
X918278Y-192564D01*
X919807Y-193731D01*
X921335Y-194314D01*
X922863D01*
X924392Y-193731D01*
X925702Y-192856D01*
X926794Y-191690D01*
G01X938835Y-194314D02*
Y-186439D01*
X934468Y-176814D01*
G01X943202D02*
X938835Y-186439D01*
G01X829032Y-149314D02*
Y-131814D01*
X833398D01*
X835145Y-132689D01*
X836455Y-133856D01*
X837547Y-135605D01*
X838420Y-137648D01*
X838638Y-140564D01*
X838420Y-143481D01*
X837547Y-145523D01*
X836455Y-147273D01*
X835145Y-148439D01*
X833398Y-149314D01*
X829032D01*
G01X848060Y-141439D02*
X855047D01*
X854392Y-139397D01*
X853300Y-138231D01*
X851772Y-137648D01*
X850243Y-137939D01*
X848933Y-138814D01*
X848060Y-140856D01*
X847623Y-142606D01*
Y-144356D01*
X848060Y-146106D01*
X849152Y-147856D01*
X850462Y-149022D01*
X851990Y-149314D01*
X853518Y-148731D01*
X855047Y-146981D01*
G01X865560Y-147273D02*
X866652Y-148439D01*
X868180Y-149314D01*
X869490D01*
X870800Y-148731D01*
X871673Y-147856D01*
X872110Y-146690D01*
X871892Y-144939D01*
X871018Y-144064D01*
X867088Y-142314D01*
X866215Y-140272D01*
X866652Y-138814D01*
X867525Y-137939D01*
X868835Y-137648D01*
X870145Y-137939D01*
X871455Y-138814D01*
G01X886335Y-137648D02*
Y-149314D01*
G01Y-132981D02*
X885898Y-132689D01*
Y-132106D01*
X886335Y-131814D01*
X886772Y-132106D01*
Y-132689D01*
X886335Y-132981D01*
G01X900778Y-153689D02*
X902307Y-154856D01*
X904053Y-155147D01*
X905581Y-154856D01*
X906892Y-153398D01*
X907765Y-151356D01*
Y-137648D01*
G01Y-139981D02*
X906892Y-138814D01*
X905581Y-137939D01*
X904053Y-137648D01*
X902307Y-138231D01*
X901215Y-139397D01*
X900341Y-141439D01*
X899905Y-143481D01*
X900123Y-145231D01*
X900997Y-147273D01*
X902307Y-148731D01*
X904053Y-149314D01*
X905363Y-149022D01*
X906892Y-147856D01*
X907765Y-146690D01*
G01X917623Y-149314D02*
Y-137648D01*
G01Y-140564D02*
X918497Y-139106D01*
X919807Y-137939D01*
X921553Y-137648D01*
X923081Y-137939D01*
X924392Y-139106D01*
X925047Y-141147D01*
Y-149314D01*
G01X935560Y-141439D02*
X942547D01*
X941892Y-139397D01*
X940800Y-138231D01*
X939272Y-137648D01*
X937743Y-137939D01*
X936433Y-138814D01*
X935560Y-140856D01*
X935123Y-142606D01*
Y-144356D01*
X935560Y-146106D01*
X936652Y-147856D01*
X937962Y-149022D01*
X939490Y-149314D01*
X941018Y-148731D01*
X942547Y-146981D01*
G01X953278Y-149314D02*
Y-137648D01*
G01Y-139981D02*
X954370Y-138814D01*
X955462Y-137939D01*
X956990Y-137648D01*
X958081Y-137939D01*
X959392Y-138814D01*
G01X1000035Y-176814D02*
X998288Y-177397D01*
X996978Y-178856D01*
X996105Y-180605D01*
X995450Y-182939D01*
X995232Y-185564D01*
X995450Y-188189D01*
X996105Y-190523D01*
X996978Y-192273D01*
X998288Y-193731D01*
X1000035Y-194314D01*
X1001781Y-193731D01*
X1003092Y-192273D01*
X1003965Y-190523D01*
X1004620Y-188189D01*
X1004838Y-185564D01*
X1004620Y-182939D01*
X1003965Y-180605D01*
X1003092Y-178856D01*
X1001781Y-177397D01*
X1000035Y-176814D01*
G01X1012732Y-190814D02*
X1014041Y-192856D01*
X1015788Y-194022D01*
X1017753Y-194314D01*
X1019500Y-194022D01*
X1021247Y-192564D01*
X1022338Y-190814D01*
X1022557Y-189064D01*
X1022120Y-187023D01*
X1020592Y-185564D01*
X1019063Y-184981D01*
X1017098D01*
G01X1019063D02*
X1020373Y-184106D01*
X1021465Y-182648D01*
X1021902Y-180898D01*
X1021465Y-179147D01*
X1020373Y-177689D01*
X1018408Y-176814D01*
X1016443Y-177106D01*
X1014478Y-178273D01*
G01X1031105Y-194897D02*
X1038965Y-176814D01*
G01X1052535Y-194314D02*
Y-176814D01*
X1049915Y-180314D01*
G01Y-194314D02*
X1055155D01*
G01X1065232Y-190814D02*
X1066541Y-192856D01*
X1068288Y-194022D01*
X1070253Y-194314D01*
X1072000Y-194022D01*
X1073747Y-192564D01*
X1074838Y-190814D01*
X1075057Y-189064D01*
X1074620Y-187023D01*
X1073092Y-185564D01*
X1071563Y-184981D01*
X1069598D01*
G01X1071563D02*
X1072873Y-184106D01*
X1073965Y-182648D01*
X1074402Y-180898D01*
X1073965Y-179147D01*
X1072873Y-177689D01*
X1070908Y-176814D01*
X1068943Y-177106D01*
X1066978Y-178273D01*
G01X1083605Y-194897D02*
X1091465Y-176814D01*
G01X1100887Y-179731D02*
X1102197Y-177981D01*
X1103725Y-177106D01*
X1105472Y-176814D01*
X1107655Y-177397D01*
X1109183Y-178856D01*
X1109620Y-180605D01*
X1109402Y-182356D01*
X1108528Y-183814D01*
X1104162Y-186731D01*
X1102197Y-188772D01*
X1100887Y-191690D01*
X1100450Y-194314D01*
X1109620D01*
G01X1122535Y-176814D02*
X1120788Y-177397D01*
X1119478Y-178856D01*
X1118605Y-180605D01*
X1117950Y-182939D01*
X1117732Y-185564D01*
X1117950Y-188189D01*
X1118605Y-190523D01*
X1119478Y-192273D01*
X1120788Y-193731D01*
X1122535Y-194314D01*
X1124281Y-193731D01*
X1125592Y-192273D01*
X1126465Y-190523D01*
X1127120Y-188189D01*
X1127338Y-185564D01*
X1127120Y-182939D01*
X1126465Y-180605D01*
X1125592Y-178856D01*
X1124281Y-177397D01*
X1122535Y-176814D01*
G01X1140035Y-194314D02*
Y-176814D01*
X1137415Y-180314D01*
G01Y-194314D02*
X1142655D01*
G01X1157098D02*
X1157535Y-190523D01*
X1158190Y-187314D01*
X1159063Y-184397D01*
X1160155Y-181189D01*
X1161902Y-176814D01*
X1153168D01*
G01X1047732Y-149314D02*
Y-131814D01*
X1052098D01*
X1053845Y-132689D01*
X1055155Y-133856D01*
X1056247Y-135605D01*
X1057120Y-137648D01*
X1057338Y-140564D01*
X1057120Y-143481D01*
X1056247Y-145523D01*
X1055155Y-147273D01*
X1053845Y-148439D01*
X1052098Y-149314D01*
X1047732D01*
G01X1073965D02*
Y-137648D01*
G01Y-139689D02*
X1073092Y-138523D01*
X1071781Y-137939D01*
X1070253Y-137648D01*
X1068725Y-138231D01*
X1067415Y-139397D01*
X1066541Y-141147D01*
X1066105Y-143481D01*
X1066541Y-145814D01*
X1067415Y-147564D01*
X1068725Y-148731D01*
X1070253Y-149314D01*
X1071781Y-149022D01*
X1073092Y-148148D01*
X1073965Y-146981D01*
G01X1087535Y-131814D02*
Y-149314D01*
G01X1084478Y-137648D02*
X1090592D01*
G01X1101760Y-141439D02*
X1108747D01*
X1108092Y-139397D01*
X1107000Y-138231D01*
X1105472Y-137648D01*
X1103943Y-137939D01*
X1102633Y-138814D01*
X1101760Y-140856D01*
X1101323Y-142606D01*
Y-144356D01*
X1101760Y-146106D01*
X1102852Y-147856D01*
X1104162Y-149022D01*
X1105690Y-149314D01*
X1107218Y-148731D01*
X1108747Y-146981D01*
G54D17*
X64300Y20100D03*
X135500Y19200D03*
X97200Y20600D03*
X102600D03*
X278574Y21070D03*
X245753Y21617D03*
X409400Y20900D03*
X442500D03*
X535700Y20500D03*
X568800Y20400D03*
X628000Y19800D03*
X661100Y19900D03*
G54D18*
X82000Y9000D03*
X59000Y47800D03*
X58494Y40465D03*
X47800Y51500D03*
X51573Y47700D03*
X96000Y10500D03*
X135300Y9500D03*
X122800Y8800D03*
X228100Y11100D03*
X260600Y13000D03*
X270500Y8900D03*
X306174Y44235D03*
X300613Y46440D03*
X296425Y49468D03*
X300349Y41423D03*
X420600Y9700D03*
X395500Y20500D03*
X420907Y46740D03*
X424263Y37986D03*
X435200Y9600D03*
X431545Y47333D03*
X428151Y42300D03*
X559800Y8900D03*
X547300Y9000D03*
X523900Y20300D03*
X555698Y37934D03*
X552364Y42400D03*
X545084Y41472D03*
X548424Y47100D03*
X582700Y20500D03*
X653620Y8412D03*
X637981Y8316D03*
X676453Y38712D03*
X676576Y44600D03*
X668361Y43924D03*
X672636Y48100D03*
G54D19*
X64300Y25700D03*
X135500Y24800D03*
X97200Y26200D03*
X102600D03*
X278574Y26670D03*
X245753Y27217D03*
X409400Y26500D03*
X442500D03*
X535700Y26100D03*
X568800Y26000D03*
X628000Y25400D03*
X661100Y25500D03*
M02*
